# BASEBOARD_FAB2 (Tioga Pass) — schematic netlist excerpt (pin names and nets, part order shuffled) for the footprints in the layout excerpt that follows; sources: Cadence DE-HDL packaged netlist, KiCad conversion of Wiwynn_Tioga_Pass_MB.brd

C1R3  CAP  0.22UF 16V 10% X7R  pkg 0402  page 106 : A = P3E_CPU0_PE3_OCP_TXN<1> ; B = P3E_OCP_CPU0_PE3_C_TXN<1>
R9P26  RES  10.0 1% CHIP  pkg 0402  page 200 : A = P12V_HSC_SENN1 ; B = A_HSC_HSN
C1M26  CAP  10UF 16V 10% X6S  pkg 0805  page 186 : A = P12V_STBY ; B = GND

(kicad_pcb
	(version 20260206)
	(generator "pcbnew")
	(generator_version "10.0")
	(general
		(thickness 1.6)
		(legacy_teardrops no)
	)
	(paper "A4")
	(title_block
		(title "Wiwynn_Tioga_Pass_MB.brd")
		(comment 1 "Tioga Pass / footprints 3978-3980 of 4770")
	)
	(layers
		(0 "F.Cu" signal "TOP")
		(4 "In1.Cu" signal "L2GND")
		(6 "In2.Cu" signal "L3")
		(8 "In3.Cu" signal "L4GND")
		(10 "In4.Cu" signal "L5")
		(12 "In5.Cu" signal "L6GND")
		(14 "In6.Cu" signal "L7VCC")
		(16 "In7.Cu" signal "L8VCC")
		(18 "In8.Cu" signal "L9GND")
		(20 "In9.Cu" signal "L10")
		(22 "In10.Cu" signal "L11GND")
		(24 "In11.Cu" signal "L12")
		(26 "In12.Cu" signal "L13GND")
		(2 "B.Cu" signal "BOTTOM")
		(9 "F.Adhes" user "F.Adhesive")
		(11 "B.Adhes" user "B.Adhesive")
		(13 "F.Paste" user "Package Geometry/Pastemask Top")
		(15 "B.Paste" user "Package Geometry/Pastemask Bottom")
		(5 "F.SilkS" user "Ref Des/Silkscreen Top")
		(7 "B.SilkS" user "Ref Des/Silkscreen Bottom")
		(1 "F.Mask" user "Board Geometry/Soldermask Top")
		(3 "B.Mask" user "Board Geometry/Soldermask Bottom")
		(17 "Dwgs.User" user "User.Drawings")
		(19 "Cmts.User" user "User.Comments")
		(21 "Eco1.User" user "User.Eco1")
		(23 "Eco2.User" user "User.Eco2")
		(25 "Edge.Cuts" user "Board Geometry/Outline")
		(27 "Margin" user)
		(31 "F.CrtYd" user "Package Geometry/Place Bound Top")
		(29 "B.CrtYd" user "Package Geometry/Place Bound Bottom")
		(35 "F.Fab" user "Ref Des/Assembly Top")
		(33 "B.Fab" user "Ref Des/Assembly Bottom")
	)
	(footprint ""
		(layer "B.Cu")
		(at 10.414 -68.0466 180)
		(property "Reference" "R9P26"
			(at 0 0 0)
			(layer "B.SilkS")
			(hide yes)
			(effects
				(font
					(size 1.27 1.27)
				)
				(justify mirror)
			)
		)
		(property "Value" ""
			(at 0 0 0)
			(layer "B.Fab")
			(effects
				(font
					(size 1.27 1.27)
				)
				(justify mirror)
			)
		)
		(duplicate_pad_numbers_are_jumpers no)
		(fp_rect
			(start -0.2794 0.9906)
			(end 0.2794 -0.1016)
			(stroke
				(width 0)
				(type default)
			)
			(fill no)
			(layer "B.CrtYd")
		)
		(fp_line
			(start 0.2794 0.9906)
			(end -0.2794 0.9906)
			(stroke
				(width 0.1)
				(type default)
			)
			(layer "B.Fab")
		)
		(fp_line
			(start 0.2794 -0.1016)
			(end 0.2794 0.9906)
			(stroke
				(width 0.1)
				(type default)
			)
			(layer "B.Fab")
		)
		(fp_line
			(start -0.2794 0.9906)
			(end -0.2794 -0.1016)
			(stroke
				(width 0.1)
				(type default)
			)
			(layer "B.Fab")
		)
		(fp_line
			(start -0.2794 -0.1016)
			(end 0.2794 -0.1016)
			(stroke
				(width 0.1)
				(type default)
			)
			(layer "B.Fab")
		)
		(pad "1" smd rect
			(at 0 0)
			(size 0.508 0.508)
			(layers "B.Cu" "B.Mask" "B.Paste")
			(net "P12V_HSC_SENN1")
		)
		(pad "2" smd rect
			(at 0 0.889)
			(size 0.508 0.508)
			(layers "B.Cu" "B.Mask" "B.Paste")
			(net "A_HSC_HSN")
		)
		(zone
			(layer "B.Cu")
			(hatch none 0.5)
			(connect_pads
				(clearance 0)
			)
			(min_thickness 0.25)
			(keepout
				(tracks allowed)
				(vias not_allowed)
				(pads allowed)
				(copperpour not_allowed)
				(footprints allowed)
			)
			(placement
				(enabled no)
				(sheetname "")
			)
			(fill
				(thermal_gap 0.5)
				(thermal_bridge_width 0.5)
				(island_removal_mode 0)
			)
			(polygon
				(pts
					(xy 10.668 -68.6816) (xy 10.16 -68.6816) (xy 10.16 -68.3006) (xy 10.668 -68.3006)
				)
			)
		)
		(zone
			(layer "B.Cu")
			(hatch none 0.5)
			(connect_pads
				(clearance 0)
			)
			(min_thickness 0.25)
			(keepout
				(tracks not_allowed)
				(vias allowed)
				(pads allowed)
				(copperpour not_allowed)
				(footprints allowed)
			)
			(placement
				(enabled no)
				(sheetname "")
			)
			(fill
				(thermal_gap 0.5)
				(thermal_bridge_width 0.5)
				(island_removal_mode 0)
			)
			(polygon
				(pts
					(xy 10.668 -68.6816) (xy 10.16 -68.6816) (xy 10.16 -68.3006) (xy 10.668 -68.3006)
				)
			)
		)
	)
	(footprint ""
		(layer "B.Cu")
		(at 487.934 -111.94542 90)
		(property "Reference" "C1M26"
			(at 0 0 90)
			(layer "B.SilkS")
			(hide yes)
			(effects
				(font
					(size 1.27 1.27)
				)
				(justify mirror)
			)
		)
		(property "Value" ""
			(at 0 0 90)
			(layer "B.Fab")
			(effects
				(font
					(size 1.27 1.27)
				)
				(justify mirror)
			)
		)
		(duplicate_pad_numbers_are_jumpers no)
		(fp_rect
			(start -0.7239 -0.2159)
			(end 0.7239 1.9939)
			(stroke
				(width 0)
				(type default)
			)
			(fill no)
			(layer "B.CrtYd")
		)
		(fp_line
			(start 0.7239 -0.2159)
			(end 0.7239 1.9939)
			(stroke
				(width 0.1)
				(type default)
			)
			(layer "B.Fab")
		)
		(fp_line
			(start -0.7239 -0.2159)
			(end 0.7239 -0.2159)
			(stroke
				(width 0.1)
				(type default)
			)
			(layer "B.Fab")
		)
		(fp_line
			(start 0.7239 1.9939)
			(end -0.7239 1.9939)
			(stroke
				(width 0.1)
				(type default)
			)
			(layer "B.Fab")
		)
		(fp_line
			(start -0.7239 1.9939)
			(end -0.7239 -0.2159)
			(stroke
				(width 0.1)
				(type default)
			)
			(layer "B.Fab")
		)
		(pad "1" smd rect
			(at 0 0 270)
			(size 1.27 1.016)
			(layers "B.Cu" "B.Mask" "B.Paste")
			(net "P12V_STBY")
		)
		(pad "2" smd rect
			(at 0 1.778 270)
			(size 1.27 1.016)
			(layers "B.Cu" "B.Mask" "B.Paste")
			(net "GND")
		)
		(zone
			(layer "B.Cu")
			(hatch none 0.5)
			(connect_pads
				(clearance 0)
			)
			(min_thickness 0.25)
			(keepout
				(tracks not_allowed)
				(vias allowed)
				(pads allowed)
				(copperpour not_allowed)
				(footprints allowed)
			)
			(placement
				(enabled no)
				(sheetname "")
			)
			(fill
				(thermal_gap 0.5)
				(thermal_bridge_width 0.5)
				(island_removal_mode 0)
			)
			(polygon
				(pts
					(xy 488.442 -111.31042) (xy 489.204 -111.31042) (xy 489.204 -112.58042) (xy 488.442 -112.58042)
				)
			)
		)
	)
	(footprint ""
		(layer "B.Cu")
		(at 460.6544 -52.457858)
		(property "Reference" "C1R3"
			(at 0 0 0)
			(layer "B.SilkS")
			(hide yes)
			(effects
				(font
					(size 1.27 1.27)
				)
				(justify mirror)
			)
		)
		(property "Value" ""
			(at 0 0 0)
			(layer "B.Fab")
			(effects
				(font
					(size 1.27 1.27)
				)
				(justify mirror)
			)
		)
		(duplicate_pad_numbers_are_jumpers no)
		(fp_poly
			(pts
				(xy -0.3048 -0.1016) (xy -0.3048 0.9906) (xy 0.3048 0.9906) (xy 0.3048 -0.1016)
			)
			(stroke
				(width 0)
				(type default)
			)
			(fill no)
			(layer "B.CrtYd")
		)
		(fp_line
			(start -0.3048 -0.1016)
			(end 0.3048 -0.1016)
			(stroke
				(width 0.1)
				(type default)
			)
			(layer "B.Fab")
		)
		(fp_line
			(start -0.3048 0.9906)
			(end -0.3048 -0.1016)
			(stroke
				(width 0.1)
				(type default)
			)
			(layer "B.Fab")
		)
		(fp_line
			(start 0.3048 -0.1016)
			(end 0.3048 0.9906)
			(stroke
				(width 0.1)
				(type default)
			)
			(layer "B.Fab")
		)
		(fp_line
			(start 0.3048 0.9906)
			(end -0.3048 0.9906)
			(stroke
				(width 0.1)
				(type default)
			)
			(layer "B.Fab")
		)
		(pad "1" smd rect
			(at 0 0 180)
			(size 0.508 0.508)
			(layers "B.Cu" "B.Mask" "B.Paste")
			(net "P3E_CPU0_PE3_OCP_TXN<1>")
		)
		(pad "2" smd rect
			(at 0 0.889 180)
			(size 0.508 0.508)
			(layers "B.Cu" "B.Mask" "B.Paste")
			(net "P3E_OCP_CPU0_PE3_C_TXN<1>")
		)
		(zone
			(layer "B.Cu")
			(hatch none 0.5)
			(connect_pads
				(clearance 0)
			)
			(min_thickness 0.25)
			(keepout
				(tracks allowed)
				(vias not_allowed)
				(pads allowed)
				(copperpour not_allowed)
				(footprints allowed)
			)
			(placement
				(enabled no)
				(sheetname "")
			)
			(fill
				(thermal_gap 0.5)
				(thermal_bridge_width 0.5)
				(island_removal_mode 0)
			)
			(polygon
				(pts
					(xy 460.9084 -52.203858) (xy 460.4004 -52.203858) (xy 460.4004 -51.822858) (xy 460.9084 -51.822858)
				)
			)
		)
		(zone
			(layer "B.Cu")
			(hatch none 0.5)
			(connect_pads
				(clearance 0)
			)
			(min_thickness 0.25)
			(keepout
				(tracks not_allowed)
				(vias allowed)
				(pads allowed)
				(copperpour not_allowed)
				(footprints allowed)
			)
			(placement
				(enabled no)
				(sheetname "")
			)
			(fill
				(thermal_gap 0.5)
				(thermal_bridge_width 0.5)
				(island_removal_mode 0)
			)
			(polygon
				(pts
					(xy 460.9084 -51.822858) (xy 460.4004 -51.822858) (xy 460.4004 -52.203858) (xy 460.9084 -52.203858)
				)
			)
		)
	)
)
